(kicad_pcb
	(version 20260206)
	(generator "pcbnew")
	(generator_version "10.0")
	(general
		(thickness 1.6)
		(legacy_teardrops no)
	)
	(paper "A4")
	(title_block
		(title "01162023_DA0F0TEBIF0_F0T_Expander_BD_F_brd_V02_OCP.brd")
		(comment 1 "Grand Teton / footprints 5489-5494 of 9728")
	)
	(layers
		(0 "F.Cu" signal "TOP")
		(4 "In1.Cu" signal "GND")
		(6 "In2.Cu" signal "VCC")
		(8 "In3.Cu" signal "VCC1")
		(10 "In4.Cu" signal "GND1")
		(12 "In5.Cu" signal "IN1")
		(14 "In6.Cu" signal "GND2")
		(16 "In7.Cu" signal "IN2")
		(18 "In8.Cu" signal "GND3")
		(20 "In9.Cu" signal "IN3")
		(22 "In10.Cu" signal "GND4")
		(24 "In11.Cu" signal "IN4")
		(26 "In12.Cu" signal "GND5")
		(28 "In13.Cu" signal "IN5")
		(30 "In14.Cu" signal "GND6")
		(32 "In15.Cu" signal "IN6")
		(34 "In16.Cu" signal "GND7")
		(2 "B.Cu" signal "BOTTOM")
		(9 "F.Adhes" user "F.Adhesive")
		(11 "B.Adhes" user "B.Adhesive")
		(13 "F.Paste" user "Package Geometry/Pastemask Top")
		(15 "B.Paste" user "Package Geometry/Pastemask Bottom")
		(5 "F.SilkS" user "Ref Des/Silkscreen Top")
		(7 "B.SilkS" user "Ref Des/Silkscreen Bottom")
		(1 "F.Mask" user "Board Geometry/Soldermask Top")
		(3 "B.Mask" user "Board Geometry/Soldermask Bottom")
		(17 "Dwgs.User" user "User.Drawings")
		(19 "Cmts.User" user "User.Comments")
		(21 "Eco1.User" user "User.Eco1")
		(23 "Eco2.User" user "User.Eco2")
		(25 "Edge.Cuts" user "Board Geometry/Outline")
		(27 "Margin" user)
		(31 "F.CrtYd" user "Package Geometry/Place Bound Top")
		(29 "B.CrtYd" user "Package Geometry/Place Bound Bottom")
		(35 "F.Fab" user "Ref Des/Assembly Top")
		(33 "B.Fab" user "Ref Des/Assembly Bottom")
	)
	(footprint ""
		(layer "F.Cu")
		(at 260.54177 -27.006296 -90)
		(property "Reference" "PR7118"
			(at 0 0 270)
			(layer "F.SilkS")
			(hide yes)
			(effects
				(font
					(size 1.27 1.27)
				)
			)
		)
		(property "Value" ""
			(at 0 0 270)
			(layer "F.Fab")
			(effects
				(font
					(size 1.27 1.27)
				)
			)
		)
		(duplicate_pad_numbers_are_jumpers no)
		(fp_line
			(start -0.7874 0.4064)
			(end -0.7874 -0.4064)
			(stroke
				(width 0.1524)
				(type default)
			)
			(layer "F.SilkS")
		)
		(fp_line
			(start 0.7874 0.4064)
			(end -0.7874 0.4064)
			(stroke
				(width 0.1524)
				(type default)
			)
			(layer "F.SilkS")
		)
		(fp_line
			(start -0.7874 -0.4064)
			(end 0.7874 -0.4064)
			(stroke
				(width 0.1524)
				(type default)
			)
			(layer "F.SilkS")
		)
		(fp_line
			(start 0.7874 -0.4064)
			(end 0.7874 0.4064)
			(stroke
				(width 0.1524)
				(type default)
			)
			(layer "F.SilkS")
		)
		(fp_line
			(start -0.67945 0.3048)
			(end -0.67945 -0.305054)
			(stroke
				(width 0.1)
				(type default)
			)
			(layer "F.Fab")
		)
		(fp_line
			(start -0.12065 0.3048)
			(end -0.67945 0.3048)
			(stroke
				(width 0.1)
				(type default)
			)
			(layer "F.Fab")
		)
		(fp_line
			(start 0.120396 0.3048)
			(end 0.120396 0.2794)
			(stroke
				(width 0.1)
				(type default)
			)
			(layer "F.Fab")
		)
		(fp_line
			(start 0.67945 0.3048)
			(end 0.120396 0.3048)
			(stroke
				(width 0.1)
				(type default)
			)
			(layer "F.Fab")
		)
		(fp_line
			(start -0.12065 0.2794)
			(end -0.12065 0.3048)
			(stroke
				(width 0.1)
				(type default)
			)
			(layer "F.Fab")
		)
		(fp_line
			(start 0.120396 0.2794)
			(end -0.12065 0.2794)
			(stroke
				(width 0.1)
				(type default)
			)
			(layer "F.Fab")
		)
		(fp_line
			(start -0.12065 -0.2794)
			(end 0.12065 -0.2794)
			(stroke
				(width 0.1)
				(type default)
			)
			(layer "F.Fab")
		)
		(fp_line
			(start 0.12065 -0.2794)
			(end 0.12065 -0.3048)
			(stroke
				(width 0.1)
				(type default)
			)
			(layer "F.Fab")
		)
		(fp_line
			(start 0.12065 -0.3048)
			(end 0.67945 -0.3048)
			(stroke
				(width 0.1)
				(type default)
			)
			(layer "F.Fab")
		)
		(fp_line
			(start 0.67945 -0.3048)
			(end 0.67945 0.3048)
			(stroke
				(width 0.1)
				(type default)
			)
			(layer "F.Fab")
		)
		(fp_line
			(start -0.67945 -0.305054)
			(end -0.12065 -0.305054)
			(stroke
				(width 0.1)
				(type default)
			)
			(layer "F.Fab")
		)
		(fp_line
			(start -0.12065 -0.305054)
			(end -0.12065 -0.2794)
			(stroke
				(width 0.1)
				(type default)
			)
			(layer "F.Fab")
		)
		(pad "1" smd circle
			(at -0.40005 0 270)
			(size 0 0)
			(layers "F.Cu" "F.Mask" "F.Paste")
			(net "P3V3_SSD9_CO_ILIMIT")
		)
		(pad "2" smd circle
			(at 0.40005 0 270)
			(size 0 0)
			(layers "F.Cu" "F.Mask" "F.Paste")
			(net "GND")
		)
	)
	(footprint ""
		(layer "F.Cu")
		(at 313.202574 -89.1159)
		(property "Reference" "C932"
			(at 0 0 0)
			(layer "F.SilkS")
			(hide yes)
			(effects
				(font
					(size 1.27 1.27)
				)
			)
		)
		(property "Value" ""
			(at 0 0 0)
			(layer "F.Fab")
			(effects
				(font
					(size 1.27 1.27)
				)
			)
		)
		(duplicate_pad_numbers_are_jumpers no)
		(fp_line
			(start -0.7874 -0.4064)
			(end 0.7874 -0.4064)
			(stroke
				(width 0.1524)
				(type default)
			)
			(layer "F.SilkS")
		)
		(fp_line
			(start -0.7874 0.4064)
			(end -0.7874 -0.4064)
			(stroke
				(width 0.1524)
				(type default)
			)
			(layer "F.SilkS")
		)
		(fp_line
			(start 0.7874 -0.4064)
			(end 0.7874 0.4064)
			(stroke
				(width 0.1524)
				(type default)
			)
			(layer "F.SilkS")
		)
		(fp_line
			(start 0.7874 0.4064)
			(end -0.7874 0.4064)
			(stroke
				(width 0.1524)
				(type default)
			)
			(layer "F.SilkS")
		)
		(fp_line
			(start -0.67945 -0.305054)
			(end -0.12065 -0.305054)
			(stroke
				(width 0.1)
				(type default)
			)
			(layer "F.Fab")
		)
		(fp_line
			(start -0.67945 0.3048)
			(end -0.67945 -0.305054)
			(stroke
				(width 0.1)
				(type default)
			)
			(layer "F.Fab")
		)
		(fp_line
			(start -0.12065 -0.305054)
			(end -0.12065 -0.2794)
			(stroke
				(width 0.1)
				(type default)
			)
			(layer "F.Fab")
		)
		(fp_line
			(start -0.12065 -0.2794)
			(end 0.12065 -0.2794)
			(stroke
				(width 0.1)
				(type default)
			)
			(layer "F.Fab")
		)
		(fp_line
			(start -0.12065 0.2794)
			(end -0.12065 0.3048)
			(stroke
				(width 0.1)
				(type default)
			)
			(layer "F.Fab")
		)
		(fp_line
			(start -0.12065 0.3048)
			(end -0.67945 0.3048)
			(stroke
				(width 0.1)
				(type default)
			)
			(layer "F.Fab")
		)
		(fp_line
			(start 0.120396 0.2794)
			(end -0.12065 0.2794)
			(stroke
				(width 0.1)
				(type default)
			)
			(layer "F.Fab")
		)
		(fp_line
			(start 0.120396 0.3048)
			(end 0.120396 0.2794)
			(stroke
				(width 0.1)
				(type default)
			)
			(layer "F.Fab")
		)
		(fp_line
			(start 0.12065 -0.3048)
			(end 0.67945 -0.3048)
			(stroke
				(width 0.1)
				(type default)
			)
			(layer "F.Fab")
		)
		(fp_line
			(start 0.12065 -0.2794)
			(end 0.12065 -0.3048)
			(stroke
				(width 0.1)
				(type default)
			)
			(layer "F.Fab")
		)
		(fp_line
			(start 0.67945 -0.3048)
			(end 0.67945 0.3048)
			(stroke
				(width 0.1)
				(type default)
			)
			(layer "F.Fab")
		)
		(fp_line
			(start 0.67945 0.3048)
			(end 0.120396 0.3048)
			(stroke
				(width 0.1)
				(type default)
			)
			(layer "F.Fab")
		)
		(pad "1" smd circle
			(at -0.40005 0)
			(size 0 0)
			(layers "F.Cu" "F.Mask" "F.Paste")
			(net "P3V3_AUX")
		)
		(pad "2" smd circle
			(at 0.40005 0)
			(size 0 0)
			(layers "F.Cu" "F.Mask" "F.Paste")
			(net "GND")
		)
	)
	(footprint ""
		(layer "F.Cu")
		(at 79.12608 -39.73576 -90)
		(property "Reference" "R5548"
			(at 0 0 270)
			(layer "F.SilkS")
			(hide yes)
			(effects
				(font
					(size 1.27 1.27)
				)
			)
		)
		(property "Value" ""
			(at 0 0 270)
			(layer "F.Fab")
			(effects
				(font
					(size 1.27 1.27)
				)
			)
		)
		(duplicate_pad_numbers_are_jumpers no)
		(fp_line
			(start -0.7874 0.4064)
			(end -0.7874 -0.4064)
			(stroke
				(width 0.1524)
				(type default)
			)
			(layer "F.SilkS")
		)
		(fp_line
			(start 0.7874 0.4064)
			(end -0.7874 0.4064)
			(stroke
				(width 0.1524)
				(type default)
			)
			(layer "F.SilkS")
		)
		(fp_line
			(start -0.7874 -0.4064)
			(end 0.7874 -0.4064)
			(stroke
				(width 0.1524)
				(type default)
			)
			(layer "F.SilkS")
		)
		(fp_line
			(start 0.7874 -0.4064)
			(end 0.7874 0.4064)
			(stroke
				(width 0.1524)
				(type default)
			)
			(layer "F.SilkS")
		)
		(fp_line
			(start -0.67945 0.3048)
			(end -0.67945 -0.305054)
			(stroke
				(width 0.1)
				(type default)
			)
			(layer "F.Fab")
		)
		(fp_line
			(start -0.12065 0.3048)
			(end -0.67945 0.3048)
			(stroke
				(width 0.1)
				(type default)
			)
			(layer "F.Fab")
		)
		(fp_line
			(start 0.120396 0.3048)
			(end 0.120396 0.2794)
			(stroke
				(width 0.1)
				(type default)
			)
			(layer "F.Fab")
		)
		(fp_line
			(start 0.67945 0.3048)
			(end 0.120396 0.3048)
			(stroke
				(width 0.1)
				(type default)
			)
			(layer "F.Fab")
		)
		(fp_line
			(start -0.12065 0.2794)
			(end -0.12065 0.3048)
			(stroke
				(width 0.1)
				(type default)
			)
			(layer "F.Fab")
		)
		(fp_line
			(start 0.120396 0.2794)
			(end -0.12065 0.2794)
			(stroke
				(width 0.1)
				(type default)
			)
			(layer "F.Fab")
		)
		(fp_line
			(start -0.12065 -0.2794)
			(end 0.12065 -0.2794)
			(stroke
				(width 0.1)
				(type default)
			)
			(layer "F.Fab")
		)
		(fp_line
			(start 0.12065 -0.2794)
			(end 0.12065 -0.3048)
			(stroke
				(width 0.1)
				(type default)
			)
			(layer "F.Fab")
		)
		(fp_line
			(start 0.12065 -0.3048)
			(end 0.67945 -0.3048)
			(stroke
				(width 0.1)
				(type default)
			)
			(layer "F.Fab")
		)
		(fp_line
			(start 0.67945 -0.3048)
			(end 0.67945 0.3048)
			(stroke
				(width 0.1)
				(type default)
			)
			(layer "F.Fab")
		)
		(fp_line
			(start -0.67945 -0.305054)
			(end -0.12065 -0.305054)
			(stroke
				(width 0.1)
				(type default)
			)
			(layer "F.Fab")
		)
		(fp_line
			(start -0.12065 -0.305054)
			(end -0.12065 -0.2794)
			(stroke
				(width 0.1)
				(type default)
			)
			(layer "F.Fab")
		)
		(pad "1" smd circle
			(at -0.40005 0 270)
			(size 0 0)
			(layers "F.Cu" "F.Mask" "F.Paste")
			(net "P3V3_AUX")
		)
		(pad "2" smd circle
			(at 0.40005 0 270)
			(size 0 0)
			(layers "F.Cu" "F.Mask" "F.Paste")
			(net "SSD3_AUX_P3V3_EN")
		)
	)
	(footprint ""
		(layer "F.Cu")
		(at 15.697962 -122.780552)
		(property "Reference" "PC450"
			(at 0 0 0)
			(layer "F.SilkS")
			(hide yes)
			(effects
				(font
					(size 1.27 1.27)
				)
			)
		)
		(property "Value" ""
			(at 0 0 0)
			(layer "F.Fab")
			(effects
				(font
					(size 1.27 1.27)
				)
			)
		)
		(duplicate_pad_numbers_are_jumpers no)
		(fp_line
			(start -0.7874 -0.4064)
			(end 0.7874 -0.4064)
			(stroke
				(width 0.1524)
				(type default)
			)
			(layer "F.SilkS")
		)
		(fp_line
			(start -0.7874 0.4064)
			(end -0.7874 -0.4064)
			(stroke
				(width 0.1524)
				(type default)
			)
			(layer "F.SilkS")
		)
		(fp_line
			(start 0.7874 -0.4064)
			(end 0.7874 0.4064)
			(stroke
				(width 0.1524)
				(type default)
			)
			(layer "F.SilkS")
		)
		(fp_line
			(start 0.7874 0.4064)
			(end -0.7874 0.4064)
			(stroke
				(width 0.1524)
				(type default)
			)
			(layer "F.SilkS")
		)
		(fp_line
			(start -0.67945 -0.305054)
			(end -0.12065 -0.305054)
			(stroke
				(width 0.1)
				(type default)
			)
			(layer "F.Fab")
		)
		(fp_line
			(start -0.67945 0.3048)
			(end -0.67945 -0.305054)
			(stroke
				(width 0.1)
				(type default)
			)
			(layer "F.Fab")
		)
		(fp_line
			(start -0.12065 -0.305054)
			(end -0.12065 -0.2794)
			(stroke
				(width 0.1)
				(type default)
			)
			(layer "F.Fab")
		)
		(fp_line
			(start -0.12065 -0.2794)
			(end 0.12065 -0.2794)
			(stroke
				(width 0.1)
				(type default)
			)
			(layer "F.Fab")
		)
		(fp_line
			(start -0.12065 0.2794)
			(end -0.12065 0.3048)
			(stroke
				(width 0.1)
				(type default)
			)
			(layer "F.Fab")
		)
		(fp_line
			(start -0.12065 0.3048)
			(end -0.67945 0.3048)
			(stroke
				(width 0.1)
				(type default)
			)
			(layer "F.Fab")
		)
		(fp_line
			(start 0.120396 0.2794)
			(end -0.12065 0.2794)
			(stroke
				(width 0.1)
				(type default)
			)
			(layer "F.Fab")
		)
		(fp_line
			(start 0.120396 0.3048)
			(end 0.120396 0.2794)
			(stroke
				(width 0.1)
				(type default)
			)
			(layer "F.Fab")
		)
		(fp_line
			(start 0.12065 -0.3048)
			(end 0.67945 -0.3048)
			(stroke
				(width 0.1)
				(type default)
			)
			(layer "F.Fab")
		)
		(fp_line
			(start 0.12065 -0.2794)
			(end 0.12065 -0.3048)
			(stroke
				(width 0.1)
				(type default)
			)
			(layer "F.Fab")
		)
		(fp_line
			(start 0.67945 -0.3048)
			(end 0.67945 0.3048)
			(stroke
				(width 0.1)
				(type default)
			)
			(layer "F.Fab")
		)
		(fp_line
			(start 0.67945 0.3048)
			(end 0.120396 0.3048)
			(stroke
				(width 0.1)
				(type default)
			)
			(layer "F.Fab")
		)
		(pad "1" smd circle
			(at -0.40005 0)
			(size 0 0)
			(layers "F.Cu" "F.Mask" "F.Paste")
			(net "P3V3_AUX")
		)
		(pad "2" smd circle
			(at 0.40005 0)
			(size 0 0)
			(layers "F.Cu" "F.Mask" "F.Paste")
			(net "GND")
		)
	)
	(footprint ""
		(layer "F.Cu")
		(at 19.223736 -152.71115 90)
		(property "Reference" "R686"
			(at 0 0 90)
			(layer "F.SilkS")
			(hide yes)
			(effects
				(font
					(size 1.27 1.27)
				)
			)
		)
		(property "Value" ""
			(at 0 0 90)
			(layer "F.Fab")
			(effects
				(font
					(size 1.27 1.27)
				)
			)
		)
		(duplicate_pad_numbers_are_jumpers no)
		(fp_line
			(start 0.7874 -0.4064)
			(end 0.7874 0.4064)
			(stroke
				(width 0.1524)
				(type default)
			)
			(layer "F.SilkS")
		)
		(fp_line
			(start -0.7874 -0.4064)
			(end 0.7874 -0.4064)
			(stroke
				(width 0.1524)
				(type default)
			)
			(layer "F.SilkS")
		)
		(fp_line
			(start 0.7874 0.4064)
			(end -0.7874 0.4064)
			(stroke
				(width 0.1524)
				(type default)
			)
			(layer "F.SilkS")
		)
		(fp_line
			(start -0.7874 0.4064)
			(end -0.7874 -0.4064)
			(stroke
				(width 0.1524)
				(type default)
			)
			(layer "F.SilkS")
		)
		(fp_line
			(start -0.12065 -0.305054)
			(end -0.12065 -0.2794)
			(stroke
				(width 0.1)
				(type default)
			)
			(layer "F.Fab")
		)
		(fp_line
			(start -0.67945 -0.305054)
			(end -0.12065 -0.305054)
			(stroke
				(width 0.1)
				(type default)
			)
			(layer "F.Fab")
		)
		(fp_line
			(start 0.67945 -0.3048)
			(end 0.67945 0.3048)
			(stroke
				(width 0.1)
				(type default)
			)
			(layer "F.Fab")
		)
		(fp_line
			(start 0.12065 -0.3048)
			(end 0.67945 -0.3048)
			(stroke
				(width 0.1)
				(type default)
			)
			(layer "F.Fab")
		)
		(fp_line
			(start 0.12065 -0.2794)
			(end 0.12065 -0.3048)
			(stroke
				(width 0.1)
				(type default)
			)
			(layer "F.Fab")
		)
		(fp_line
			(start -0.12065 -0.2794)
			(end 0.12065 -0.2794)
			(stroke
				(width 0.1)
				(type default)
			)
			(layer "F.Fab")
		)
		(fp_line
			(start 0.120396 0.2794)
			(end -0.12065 0.2794)
			(stroke
				(width 0.1)
				(type default)
			)
			(layer "F.Fab")
		)
		(fp_line
			(start -0.12065 0.2794)
			(end -0.12065 0.3048)
			(stroke
				(width 0.1)
				(type default)
			)
			(layer "F.Fab")
		)
		(fp_line
			(start 0.67945 0.3048)
			(end 0.120396 0.3048)
			(stroke
				(width 0.1)
				(type default)
			)
			(layer "F.Fab")
		)
		(fp_line
			(start 0.120396 0.3048)
			(end 0.120396 0.2794)
			(stroke
				(width 0.1)
				(type default)
			)
			(layer "F.Fab")
		)
		(fp_line
			(start -0.12065 0.3048)
			(end -0.67945 0.3048)
			(stroke
				(width 0.1)
				(type default)
			)
			(layer "F.Fab")
		)
		(fp_line
			(start -0.67945 0.3048)
			(end -0.67945 -0.305054)
			(stroke
				(width 0.1)
				(type default)
			)
			(layer "F.Fab")
		)
		(pad "1" smd circle
			(at -0.40005 0 90)
			(size 0 0)
			(layers "F.Cu" "F.Mask" "F.Paste")
			(net "NIC0_ADC_A0")
		)
		(pad "2" smd circle
			(at 0.40005 0 90)
			(size 0 0)
			(layers "F.Cu" "F.Mask" "F.Paste")
			(net "GND")
		)
	)
	(footprint ""
		(layer "F.Cu")
		(at 230.749094 -177.74158 180)
		(property "Reference" "C3646"
			(at 0 0 180)
			(layer "F.SilkS")
			(hide yes)
			(effects
				(font
					(size 1.27 1.27)
				)
			)
		)
		(property "Value" ""
			(at 0 0 180)
			(layer "F.Fab")
			(effects
				(font
					(size 1.27 1.27)
				)
			)
		)
		(duplicate_pad_numbers_are_jumpers no)
		(fp_line
			(start 0.7874 0.4064)
			(end -0.7874 0.4064)
			(stroke
				(width 0.1524)
				(type default)
			)
			(layer "F.SilkS")
		)
		(fp_line
			(start 0.7874 -0.4064)
			(end 0.7874 0.4064)
			(stroke
				(width 0.1524)
				(type default)
			)
			(layer "F.SilkS")
		)
		(fp_line
			(start -0.7874 0.4064)
			(end -0.7874 -0.4064)
			(stroke
				(width 0.1524)
				(type default)
			)
			(layer "F.SilkS")
		)
		(fp_line
			(start -0.7874 -0.4064)
			(end 0.7874 -0.4064)
			(stroke
				(width 0.1524)
				(type default)
			)
			(layer "F.SilkS")
		)
		(fp_line
			(start 0.67945 0.3048)
			(end 0.120396 0.3048)
			(stroke
				(width 0.1)
				(type default)
			)
			(layer "F.Fab")
		)
		(fp_line
			(start 0.67945 -0.3048)
			(end 0.67945 0.3048)
			(stroke
				(width 0.1)
				(type default)
			)
			(layer "F.Fab")
		)
		(fp_line
			(start 0.12065 -0.2794)
			(end 0.12065 -0.3048)
			(stroke
				(width 0.1)
				(type default)
			)
			(layer "F.Fab")
		)
		(fp_line
			(start 0.12065 -0.3048)
			(end 0.67945 -0.3048)
			(stroke
				(width 0.1)
				(type default)
			)
			(layer "F.Fab")
		)
		(fp_line
			(start 0.120396 0.3048)
			(end 0.120396 0.2794)
			(stroke
				(width 0.1)
				(type default)
			)
			(layer "F.Fab")
		)
		(fp_line
			(start 0.120396 0.2794)
			(end -0.12065 0.2794)
			(stroke
				(width 0.1)
				(type default)
			)
			(layer "F.Fab")
		)
		(fp_line
			(start -0.12065 0.3048)
			(end -0.67945 0.3048)
			(stroke
				(width 0.1)
				(type default)
			)
			(layer "F.Fab")
		)
		(fp_line
			(start -0.12065 0.2794)
			(end -0.12065 0.3048)
			(stroke
				(width 0.1)
				(type default)
			)
			(layer "F.Fab")
		)
		(fp_line
			(start -0.12065 -0.2794)
			(end 0.12065 -0.2794)
			(stroke
				(width 0.1)
				(type default)
			)
			(layer "F.Fab")
		)
		(fp_line
			(start -0.12065 -0.305054)
			(end -0.12065 -0.2794)
			(stroke
				(width 0.1)
				(type default)
			)
			(layer "F.Fab")
		)
		(fp_line
			(start -0.67945 0.3048)
			(end -0.67945 -0.305054)
			(stroke
				(width 0.1)
				(type default)
			)
			(layer "F.Fab")
		)
		(fp_line
			(start -0.67945 -0.305054)
			(end -0.12065 -0.305054)
			(stroke
				(width 0.1)
				(type default)
			)
			(layer "F.Fab")
		)
		(pad "1" smd circle
			(at -0.40005 0 180)
			(size 0 0)
			(layers "F.Cu" "F.Mask" "F.Paste")
			(net "GND")
		)
		(pad "2" smd circle
			(at 0.40005 0 180)
			(size 0 0)
			(layers "F.Cu" "F.Mask" "F.Paste")
			(net "P3V3_AUX")
		)
	)
)
